(kicad_pcb
	(version 20260206)
	(generator "pcbnew")
	(generator_version "10.0")
	(general
		(thickness 1.6)
		(legacy_teardrops no)
	)
	(paper "A4")
	(title_block
		(title "04192023_DAF0TMB3IC0_F0TG_MB_C_brd_V02_OCP.brd")
		(comment 1 "Grand Teton / footprints 4480-4485 of 8354")
	)
	(layers
		(0 "F.Cu" signal "TOP")
		(4 "In1.Cu" signal "GND")
		(6 "In2.Cu" signal "IN1")
		(8 "In3.Cu" signal "GND1")
		(10 "In4.Cu" signal "IN2")
		(12 "In5.Cu" signal "GND2")
		(14 "In6.Cu" signal "IN3")
		(16 "In7.Cu" signal "GND3")
		(18 "In8.Cu" signal "VCC")
		(20 "In9.Cu" signal "VCC1")
		(22 "In10.Cu" signal "GND4")
		(24 "In11.Cu" signal "IN4")
		(26 "In12.Cu" signal "GND5")
		(28 "In13.Cu" signal "IN5")
		(30 "In14.Cu" signal "GND6")
		(32 "In15.Cu" signal "IN6")
		(34 "In16.Cu" signal "GND7")
		(2 "B.Cu" signal "BOTTOM")
		(9 "F.Adhes" user "F.Adhesive")
		(11 "B.Adhes" user "B.Adhesive")
		(13 "F.Paste" user "Package Geometry/Pastemask Top")
		(15 "B.Paste" user "Package Geometry/Pastemask Bottom")
		(5 "F.SilkS" user "Ref Des/Silkscreen Top")
		(7 "B.SilkS" user "Ref Des/Silkscreen Bottom")
		(1 "F.Mask" user "Board Geometry/Soldermask Top")
		(3 "B.Mask" user "Board Geometry/Soldermask Bottom")
		(17 "Dwgs.User" user "User.Drawings")
		(19 "Cmts.User" user "User.Comments")
		(21 "Eco1.User" user "User.Eco1")
		(23 "Eco2.User" user "User.Eco2")
		(25 "Edge.Cuts" user "Board Geometry/Outline")
		(27 "Margin" user)
		(31 "F.CrtYd" user "Package Geometry/Place Bound Top")
		(29 "B.CrtYd" user "Package Geometry/Place Bound Bottom")
		(35 "F.Fab" user "Ref Des/Assembly Top")
		(33 "B.Fab" user "Ref Des/Assembly Bottom")
	)
	(footprint ""
		(layer "F.Cu")
		(at 26.793444 -425.593256 180)
		(property "Reference" "R3284"
			(at 0 0 180)
			(layer "F.SilkS")
			(hide yes)
			(effects
				(font
					(size 1.27 1.27)
				)
			)
		)
		(property "Value" ""
			(at 0 0 180)
			(layer "F.Fab")
			(effects
				(font
					(size 1.27 1.27)
				)
			)
		)
		(duplicate_pad_numbers_are_jumpers no)
		(fp_line
			(start 0.7874 0.4064)
			(end -0.7874 0.4064)
			(stroke
				(width 0.1524)
				(type default)
			)
			(layer "F.SilkS")
		)
		(fp_line
			(start 0.7874 -0.4064)
			(end 0.7874 0.4064)
			(stroke
				(width 0.1524)
				(type default)
			)
			(layer "F.SilkS")
		)
		(fp_line
			(start -0.7874 0.4064)
			(end -0.7874 -0.4064)
			(stroke
				(width 0.1524)
				(type default)
			)
			(layer "F.SilkS")
		)
		(fp_line
			(start -0.7874 -0.4064)
			(end 0.7874 -0.4064)
			(stroke
				(width 0.1524)
				(type default)
			)
			(layer "F.SilkS")
		)
		(fp_line
			(start 0.67945 0.3048)
			(end 0.120396 0.3048)
			(stroke
				(width 0.1)
				(type default)
			)
			(layer "F.Fab")
		)
		(fp_line
			(start 0.67945 -0.3048)
			(end 0.67945 0.3048)
			(stroke
				(width 0.1)
				(type default)
			)
			(layer "F.Fab")
		)
		(fp_line
			(start 0.12065 -0.2794)
			(end 0.12065 -0.3048)
			(stroke
				(width 0.1)
				(type default)
			)
			(layer "F.Fab")
		)
		(fp_line
			(start 0.12065 -0.3048)
			(end 0.67945 -0.3048)
			(stroke
				(width 0.1)
				(type default)
			)
			(layer "F.Fab")
		)
		(fp_line
			(start 0.120396 0.3048)
			(end 0.120396 0.2794)
			(stroke
				(width 0.1)
				(type default)
			)
			(layer "F.Fab")
		)
		(fp_line
			(start 0.120396 0.2794)
			(end -0.12065 0.2794)
			(stroke
				(width 0.1)
				(type default)
			)
			(layer "F.Fab")
		)
		(fp_line
			(start -0.12065 0.3048)
			(end -0.67945 0.3048)
			(stroke
				(width 0.1)
				(type default)
			)
			(layer "F.Fab")
		)
		(fp_line
			(start -0.12065 0.2794)
			(end -0.12065 0.3048)
			(stroke
				(width 0.1)
				(type default)
			)
			(layer "F.Fab")
		)
		(fp_line
			(start -0.12065 -0.2794)
			(end 0.12065 -0.2794)
			(stroke
				(width 0.1)
				(type default)
			)
			(layer "F.Fab")
		)
		(fp_line
			(start -0.12065 -0.305054)
			(end -0.12065 -0.2794)
			(stroke
				(width 0.1)
				(type default)
			)
			(layer "F.Fab")
		)
		(fp_line
			(start -0.67945 0.3048)
			(end -0.67945 -0.305054)
			(stroke
				(width 0.1)
				(type default)
			)
			(layer "F.Fab")
		)
		(fp_line
			(start -0.67945 -0.305054)
			(end -0.12065 -0.305054)
			(stroke
				(width 0.1)
				(type default)
			)
			(layer "F.Fab")
		)
		(pad "1" smd circle
			(at -0.40005 0 180)
			(size 0 0)
			(layers "F.Cu" "F.Mask" "F.Paste")
			(net "FM_P2E_EQB0")
		)
		(pad "2" smd circle
			(at 0.40005 0 180)
			(size 0 0)
			(layers "F.Cu" "F.Mask" "F.Paste")
			(net "GND")
		)
	)
	(footprint ""
		(layer "F.Cu")
		(at 168.656 -433.878736)
		(property "Reference" "R2672"
			(at 0 0 0)
			(layer "F.SilkS")
			(hide yes)
			(effects
				(font
					(size 1.27 1.27)
				)
			)
		)
		(property "Value" ""
			(at 0 0 0)
			(layer "F.Fab")
			(effects
				(font
					(size 1.27 1.27)
				)
			)
		)
		(duplicate_pad_numbers_are_jumpers no)
		(fp_line
			(start -0.7874 -0.4064)
			(end 0.7874 -0.4064)
			(stroke
				(width 0.1524)
				(type default)
			)
			(layer "F.SilkS")
		)
		(fp_line
			(start -0.7874 0.4064)
			(end -0.7874 -0.4064)
			(stroke
				(width 0.1524)
				(type default)
			)
			(layer "F.SilkS")
		)
		(fp_line
			(start 0.7874 -0.4064)
			(end 0.7874 0.4064)
			(stroke
				(width 0.1524)
				(type default)
			)
			(layer "F.SilkS")
		)
		(fp_line
			(start 0.7874 0.4064)
			(end -0.7874 0.4064)
			(stroke
				(width 0.1524)
				(type default)
			)
			(layer "F.SilkS")
		)
		(fp_line
			(start -0.67945 -0.305054)
			(end -0.12065 -0.305054)
			(stroke
				(width 0.1)
				(type default)
			)
			(layer "F.Fab")
		)
		(fp_line
			(start -0.67945 0.3048)
			(end -0.67945 -0.305054)
			(stroke
				(width 0.1)
				(type default)
			)
			(layer "F.Fab")
		)
		(fp_line
			(start -0.12065 -0.305054)
			(end -0.12065 -0.2794)
			(stroke
				(width 0.1)
				(type default)
			)
			(layer "F.Fab")
		)
		(fp_line
			(start -0.12065 -0.2794)
			(end 0.12065 -0.2794)
			(stroke
				(width 0.1)
				(type default)
			)
			(layer "F.Fab")
		)
		(fp_line
			(start -0.12065 0.2794)
			(end -0.12065 0.3048)
			(stroke
				(width 0.1)
				(type default)
			)
			(layer "F.Fab")
		)
		(fp_line
			(start -0.12065 0.3048)
			(end -0.67945 0.3048)
			(stroke
				(width 0.1)
				(type default)
			)
			(layer "F.Fab")
		)
		(fp_line
			(start 0.120396 0.2794)
			(end -0.12065 0.2794)
			(stroke
				(width 0.1)
				(type default)
			)
			(layer "F.Fab")
		)
		(fp_line
			(start 0.120396 0.3048)
			(end 0.120396 0.2794)
			(stroke
				(width 0.1)
				(type default)
			)
			(layer "F.Fab")
		)
		(fp_line
			(start 0.12065 -0.3048)
			(end 0.67945 -0.3048)
			(stroke
				(width 0.1)
				(type default)
			)
			(layer "F.Fab")
		)
		(fp_line
			(start 0.12065 -0.2794)
			(end 0.12065 -0.3048)
			(stroke
				(width 0.1)
				(type default)
			)
			(layer "F.Fab")
		)
		(fp_line
			(start 0.67945 -0.3048)
			(end 0.67945 0.3048)
			(stroke
				(width 0.1)
				(type default)
			)
			(layer "F.Fab")
		)
		(fp_line
			(start 0.67945 0.3048)
			(end 0.120396 0.3048)
			(stroke
				(width 0.1)
				(type default)
			)
			(layer "F.Fab")
		)
		(pad "1" smd circle
			(at -0.40005 0)
			(size 0 0)
			(layers "F.Cu" "F.Mask" "F.Paste")
			(net "SMB_BMC_SWB_BUF_R_SDA")
		)
		(pad "2" smd circle
			(at 0.40005 0)
			(size 0 0)
			(layers "F.Cu" "F.Mask" "F.Paste")
			(net "SMB_BMC_SWB_BUF_SDA")
		)
	)
	(footprint ""
		(layer "F.Cu")
		(at 312.330592 -346.866464 -90)
		(property "Reference" "PC117_4"
			(at 0 0 270)
			(layer "F.SilkS")
			(hide yes)
			(effects
				(font
					(size 1.27 1.27)
				)
			)
		)
		(property "Value" ""
			(at 0 0 270)
			(layer "F.Fab")
			(effects
				(font
					(size 1.27 1.27)
				)
			)
		)
		(duplicate_pad_numbers_are_jumpers no)
		(fp_line
			(start -0.7874 0.4064)
			(end -0.7874 -0.4064)
			(stroke
				(width 0.1524)
				(type default)
			)
			(layer "F.SilkS")
		)
		(fp_line
			(start 0.7874 0.4064)
			(end -0.7874 0.4064)
			(stroke
				(width 0.1524)
				(type default)
			)
			(layer "F.SilkS")
		)
		(fp_line
			(start -0.7874 -0.4064)
			(end 0.7874 -0.4064)
			(stroke
				(width 0.1524)
				(type default)
			)
			(layer "F.SilkS")
		)
		(fp_line
			(start 0.7874 -0.4064)
			(end 0.7874 0.4064)
			(stroke
				(width 0.1524)
				(type default)
			)
			(layer "F.SilkS")
		)
		(fp_line
			(start -0.67945 0.3048)
			(end -0.67945 -0.305054)
			(stroke
				(width 0.1)
				(type default)
			)
			(layer "F.Fab")
		)
		(fp_line
			(start -0.12065 0.3048)
			(end -0.67945 0.3048)
			(stroke
				(width 0.1)
				(type default)
			)
			(layer "F.Fab")
		)
		(fp_line
			(start 0.120396 0.3048)
			(end 0.120396 0.2794)
			(stroke
				(width 0.1)
				(type default)
			)
			(layer "F.Fab")
		)
		(fp_line
			(start 0.67945 0.3048)
			(end 0.120396 0.3048)
			(stroke
				(width 0.1)
				(type default)
			)
			(layer "F.Fab")
		)
		(fp_line
			(start -0.12065 0.2794)
			(end -0.12065 0.3048)
			(stroke
				(width 0.1)
				(type default)
			)
			(layer "F.Fab")
		)
		(fp_line
			(start 0.120396 0.2794)
			(end -0.12065 0.2794)
			(stroke
				(width 0.1)
				(type default)
			)
			(layer "F.Fab")
		)
		(fp_line
			(start -0.12065 -0.2794)
			(end 0.12065 -0.2794)
			(stroke
				(width 0.1)
				(type default)
			)
			(layer "F.Fab")
		)
		(fp_line
			(start 0.12065 -0.2794)
			(end 0.12065 -0.3048)
			(stroke
				(width 0.1)
				(type default)
			)
			(layer "F.Fab")
		)
		(fp_line
			(start 0.12065 -0.3048)
			(end 0.67945 -0.3048)
			(stroke
				(width 0.1)
				(type default)
			)
			(layer "F.Fab")
		)
		(fp_line
			(start 0.67945 -0.3048)
			(end 0.67945 0.3048)
			(stroke
				(width 0.1)
				(type default)
			)
			(layer "F.Fab")
		)
		(fp_line
			(start -0.67945 -0.305054)
			(end -0.12065 -0.305054)
			(stroke
				(width 0.1)
				(type default)
			)
			(layer "F.Fab")
		)
		(fp_line
			(start -0.12065 -0.305054)
			(end -0.12065 -0.2794)
			(stroke
				(width 0.1)
				(type default)
			)
			(layer "F.Fab")
		)
		(pad "1" smd circle
			(at -0.40005 0 270)
			(size 0 0)
			(layers "F.Cu" "F.Mask" "F.Paste")
			(net "SW_P12V_AUX_PVDDCR_CPU1_P0_FLT")
		)
		(pad "2" smd circle
			(at 0.40005 0 270)
			(size 0 0)
			(layers "F.Cu" "F.Mask" "F.Paste")
			(net "GND")
		)
	)
	(footprint ""
		(layer "F.Cu")
		(at 95.88373 -37.865558 180)
		(property "Reference" "C1822"
			(at 0 0 180)
			(layer "F.SilkS")
			(hide yes)
			(effects
				(font
					(size 1.27 1.27)
				)
			)
		)
		(property "Value" ""
			(at 0 0 180)
			(layer "F.Fab")
			(effects
				(font
					(size 1.27 1.27)
				)
			)
		)
		(duplicate_pad_numbers_are_jumpers no)
		(fp_line
			(start 0.7874 0.4064)
			(end -0.7874 0.4064)
			(stroke
				(width 0.1524)
				(type default)
			)
			(layer "F.SilkS")
		)
		(fp_line
			(start 0.7874 -0.4064)
			(end 0.7874 0.4064)
			(stroke
				(width 0.1524)
				(type default)
			)
			(layer "F.SilkS")
		)
		(fp_line
			(start -0.7874 0.4064)
			(end -0.7874 -0.4064)
			(stroke
				(width 0.1524)
				(type default)
			)
			(layer "F.SilkS")
		)
		(fp_line
			(start -0.7874 -0.4064)
			(end 0.7874 -0.4064)
			(stroke
				(width 0.1524)
				(type default)
			)
			(layer "F.SilkS")
		)
		(fp_line
			(start 0.67945 0.3048)
			(end 0.120396 0.3048)
			(stroke
				(width 0.1)
				(type default)
			)
			(layer "F.Fab")
		)
		(fp_line
			(start 0.67945 -0.3048)
			(end 0.67945 0.3048)
			(stroke
				(width 0.1)
				(type default)
			)
			(layer "F.Fab")
		)
		(fp_line
			(start 0.12065 -0.2794)
			(end 0.12065 -0.3048)
			(stroke
				(width 0.1)
				(type default)
			)
			(layer "F.Fab")
		)
		(fp_line
			(start 0.12065 -0.3048)
			(end 0.67945 -0.3048)
			(stroke
				(width 0.1)
				(type default)
			)
			(layer "F.Fab")
		)
		(fp_line
			(start 0.120396 0.3048)
			(end 0.120396 0.2794)
			(stroke
				(width 0.1)
				(type default)
			)
			(layer "F.Fab")
		)
		(fp_line
			(start 0.120396 0.2794)
			(end -0.12065 0.2794)
			(stroke
				(width 0.1)
				(type default)
			)
			(layer "F.Fab")
		)
		(fp_line
			(start -0.12065 0.3048)
			(end -0.67945 0.3048)
			(stroke
				(width 0.1)
				(type default)
			)
			(layer "F.Fab")
		)
		(fp_line
			(start -0.12065 0.2794)
			(end -0.12065 0.3048)
			(stroke
				(width 0.1)
				(type default)
			)
			(layer "F.Fab")
		)
		(fp_line
			(start -0.12065 -0.2794)
			(end 0.12065 -0.2794)
			(stroke
				(width 0.1)
				(type default)
			)
			(layer "F.Fab")
		)
		(fp_line
			(start -0.12065 -0.305054)
			(end -0.12065 -0.2794)
			(stroke
				(width 0.1)
				(type default)
			)
			(layer "F.Fab")
		)
		(fp_line
			(start -0.67945 0.3048)
			(end -0.67945 -0.305054)
			(stroke
				(width 0.1)
				(type default)
			)
			(layer "F.Fab")
		)
		(fp_line
			(start -0.67945 -0.305054)
			(end -0.12065 -0.305054)
			(stroke
				(width 0.1)
				(type default)
			)
			(layer "F.Fab")
		)
		(pad "1" smd circle
			(at -0.40005 0 180)
			(size 0 0)
			(layers "F.Cu" "F.Mask" "F.Paste")
			(net "P3V3_AUX")
		)
		(pad "2" smd circle
			(at 0.40005 0 180)
			(size 0 0)
			(layers "F.Cu" "F.Mask" "F.Paste")
			(net "GND")
		)
	)
	(footprint ""
		(layer "F.Cu")
		(at 314.567316 -111.57077 180)
		(property "Reference" "R121"
			(at 0 0 180)
			(layer "F.SilkS")
			(hide yes)
			(effects
				(font
					(size 1.27 1.27)
				)
			)
		)
		(property "Value" ""
			(at 0 0 180)
			(layer "F.Fab")
			(effects
				(font
					(size 1.27 1.27)
				)
			)
		)
		(duplicate_pad_numbers_are_jumpers no)
		(fp_line
			(start 0.7874 0.4064)
			(end -0.7874 0.4064)
			(stroke
				(width 0.1524)
				(type default)
			)
			(layer "F.SilkS")
		)
		(fp_line
			(start 0.7874 -0.4064)
			(end 0.7874 0.4064)
			(stroke
				(width 0.1524)
				(type default)
			)
			(layer "F.SilkS")
		)
		(fp_line
			(start -0.7874 0.4064)
			(end -0.7874 -0.4064)
			(stroke
				(width 0.1524)
				(type default)
			)
			(layer "F.SilkS")
		)
		(fp_line
			(start -0.7874 -0.4064)
			(end 0.7874 -0.4064)
			(stroke
				(width 0.1524)
				(type default)
			)
			(layer "F.SilkS")
		)
		(fp_line
			(start 0.67945 0.3048)
			(end 0.120396 0.3048)
			(stroke
				(width 0.1)
				(type default)
			)
			(layer "F.Fab")
		)
		(fp_line
			(start 0.67945 -0.3048)
			(end 0.67945 0.3048)
			(stroke
				(width 0.1)
				(type default)
			)
			(layer "F.Fab")
		)
		(fp_line
			(start 0.12065 -0.2794)
			(end 0.12065 -0.3048)
			(stroke
				(width 0.1)
				(type default)
			)
			(layer "F.Fab")
		)
		(fp_line
			(start 0.12065 -0.3048)
			(end 0.67945 -0.3048)
			(stroke
				(width 0.1)
				(type default)
			)
			(layer "F.Fab")
		)
		(fp_line
			(start 0.120396 0.3048)
			(end 0.120396 0.2794)
			(stroke
				(width 0.1)
				(type default)
			)
			(layer "F.Fab")
		)
		(fp_line
			(start 0.120396 0.2794)
			(end -0.12065 0.2794)
			(stroke
				(width 0.1)
				(type default)
			)
			(layer "F.Fab")
		)
		(fp_line
			(start -0.12065 0.3048)
			(end -0.67945 0.3048)
			(stroke
				(width 0.1)
				(type default)
			)
			(layer "F.Fab")
		)
		(fp_line
			(start -0.12065 0.2794)
			(end -0.12065 0.3048)
			(stroke
				(width 0.1)
				(type default)
			)
			(layer "F.Fab")
		)
		(fp_line
			(start -0.12065 -0.2794)
			(end 0.12065 -0.2794)
			(stroke
				(width 0.1)
				(type default)
			)
			(layer "F.Fab")
		)
		(fp_line
			(start -0.12065 -0.305054)
			(end -0.12065 -0.2794)
			(stroke
				(width 0.1)
				(type default)
			)
			(layer "F.Fab")
		)
		(fp_line
			(start -0.67945 0.3048)
			(end -0.67945 -0.305054)
			(stroke
				(width 0.1)
				(type default)
			)
			(layer "F.Fab")
		)
		(fp_line
			(start -0.67945 -0.305054)
			(end -0.12065 -0.305054)
			(stroke
				(width 0.1)
				(type default)
			)
			(layer "F.Fab")
		)
		(pad "1" smd circle
			(at -0.40005 0 180)
			(size 0 0)
			(layers "F.Cu" "F.Mask" "F.Paste")
			(net "SMB_FRU_3V3AUX_SCL")
		)
		(pad "2" smd circle
			(at 0.40005 0 180)
			(size 0 0)
			(layers "F.Cu" "F.Mask" "F.Paste")
			(net "SMB_CPU_FRU_3V3AUX_SCL")
		)
	)
	(footprint ""
		(layer "F.Cu")
		(at 386.211826 -62.0395 180)
		(property "Reference" "R1631"
			(at 0 0 180)
			(layer "F.SilkS")
			(hide yes)
			(effects
				(font
					(size 1.27 1.27)
				)
			)
		)
		(property "Value" ""
			(at 0 0 180)
			(layer "F.Fab")
			(effects
				(font
					(size 1.27 1.27)
				)
			)
		)
		(duplicate_pad_numbers_are_jumpers no)
		(fp_line
			(start 0.7874 0.4064)
			(end -0.7874 0.4064)
			(stroke
				(width 0.1524)
				(type default)
			)
			(layer "F.SilkS")
		)
		(fp_line
			(start 0.7874 -0.4064)
			(end 0.7874 0.4064)
			(stroke
				(width 0.1524)
				(type default)
			)
			(layer "F.SilkS")
		)
		(fp_line
			(start -0.7874 0.4064)
			(end -0.7874 -0.4064)
			(stroke
				(width 0.1524)
				(type default)
			)
			(layer "F.SilkS")
		)
		(fp_line
			(start -0.7874 -0.4064)
			(end 0.7874 -0.4064)
			(stroke
				(width 0.1524)
				(type default)
			)
			(layer "F.SilkS")
		)
		(fp_line
			(start 0.67945 0.3048)
			(end 0.120396 0.3048)
			(stroke
				(width 0.1)
				(type default)
			)
			(layer "F.Fab")
		)
		(fp_line
			(start 0.67945 -0.3048)
			(end 0.67945 0.3048)
			(stroke
				(width 0.1)
				(type default)
			)
			(layer "F.Fab")
		)
		(fp_line
			(start 0.12065 -0.2794)
			(end 0.12065 -0.3048)
			(stroke
				(width 0.1)
				(type default)
			)
			(layer "F.Fab")
		)
		(fp_line
			(start 0.12065 -0.3048)
			(end 0.67945 -0.3048)
			(stroke
				(width 0.1)
				(type default)
			)
			(layer "F.Fab")
		)
		(fp_line
			(start 0.120396 0.3048)
			(end 0.120396 0.2794)
			(stroke
				(width 0.1)
				(type default)
			)
			(layer "F.Fab")
		)
		(fp_line
			(start 0.120396 0.2794)
			(end -0.12065 0.2794)
			(stroke
				(width 0.1)
				(type default)
			)
			(layer "F.Fab")
		)
		(fp_line
			(start -0.12065 0.3048)
			(end -0.67945 0.3048)
			(stroke
				(width 0.1)
				(type default)
			)
			(layer "F.Fab")
		)
		(fp_line
			(start -0.12065 0.2794)
			(end -0.12065 0.3048)
			(stroke
				(width 0.1)
				(type default)
			)
			(layer "F.Fab")
		)
		(fp_line
			(start -0.12065 -0.2794)
			(end 0.12065 -0.2794)
			(stroke
				(width 0.1)
				(type default)
			)
			(layer "F.Fab")
		)
		(fp_line
			(start -0.12065 -0.305054)
			(end -0.12065 -0.2794)
			(stroke
				(width 0.1)
				(type default)
			)
			(layer "F.Fab")
		)
		(fp_line
			(start -0.67945 0.3048)
			(end -0.67945 -0.305054)
			(stroke
				(width 0.1)
				(type default)
			)
			(layer "F.Fab")
		)
		(fp_line
			(start -0.67945 -0.305054)
			(end -0.12065 -0.305054)
			(stroke
				(width 0.1)
				(type default)
			)
			(layer "F.Fab")
		)
		(pad "1" smd circle
			(at -0.40005 0 180)
			(size 0 0)
			(layers "F.Cu" "F.Mask" "F.Paste")
			(net "HDT_HDR_DBREQ_R_N")
		)
		(pad "2" smd circle
			(at 0.40005 0 180)
			(size 0 0)
			(layers "F.Cu" "F.Mask" "F.Paste")
			(net "HDT_HDR_DBREQ_N")
		)
	)
)
